(kicad_pcb
	(version 20241229)
	(generator "pcbnew")
	(generator_version "9.0")
	(general
		(thickness 1.599998)
		(legacy_teardrops no)
	)
	(paper "A4")
	(title_block
		(title "Artix - Datacenter Secure Control Module (DC-SCM)")
		(date "2024-11-06")
		(rev "1.1.3")
		(comment 9 "footprints 47-51 of 544")
	)
	(layers
		(0 "F.Cu" signal)
		(4 "In1.Cu" signal)
		(6 "In2.Cu" signal)
		(8 "In3.Cu" signal)
		(10 "In4.Cu" signal)
		(12 "In5.Cu" signal)
		(14 "In6.Cu" signal)
		(2 "B.Cu" signal)
		(9 "F.Adhes" user "F.Adhesive")
		(11 "B.Adhes" user "B.Adhesive")
		(13 "F.Paste" user)
		(15 "B.Paste" user)
		(5 "F.SilkS" user "F.Silkscreen")
		(7 "B.SilkS" user "B.Silkscreen")
		(1 "F.Mask" user)
		(3 "B.Mask" user)
		(17 "Dwgs.User" user "User.Drawings")
		(19 "Cmts.User" user "User.Comments")
		(21 "Eco1.User" user "User.Eco1")
		(23 "Eco2.User" user "User.Eco2")
		(25 "Edge.Cuts" user)
		(27 "Margin" user)
		(31 "F.CrtYd" user "F.Courtyard")
		(29 "B.CrtYd" user "B.Courtyard")
		(35 "F.Fab" user)
		(33 "B.Fab" user)
	)
	(footprint "antmicro-footprints:C_0402_1005Metric"
		(layer "F.Cu")
		(at 99.375 159.775 90)
		(descr "Capacitor SMD 0402")
		(tags "capacitor SMD 0402")
		(property "Reference" "C46"
			(at -1.2 -1.6 90)
			(layer "F.SilkS")
			(effects
				(font
					(size 0.7 0.7)
					(thickness 0.15)
				)
				(justify left bottom)
			)
		)
		(property "Value" "C_100n_6V3_0402"
			(at 0 1.4 90)
			(layer "F.Fab")
			(effects
				(font
					(size 0.7 0.7)
					(thickness 0.15)
				)
				(justify left bottom)
			)
		)
		(property "Datasheet" "https://www.passivecomponent.com/wp-content/uploads/datasheet/WTC_MLCC_General_Purpose.pdf"
			(at 0 0 90)
			(layer "F.Fab")
			(hide yes)
			(effects
				(font
					(size 1.27 1.27)
					(thickness 0.15)
				)
			)
		)
		(property "Description" "SMT Multilayer Ceramic Capacitor, 0.1 µF, 6.3 V, 0402 [1005 Metric], ± 10%, X5R, Walsin MLCC"
			(at 0 0 90)
			(layer "F.Fab")
			(hide yes)
			(effects
				(font
					(size 1.27 1.27)
					(thickness 0.15)
				)
			)
		)
		(property "Author" "Antmicro"
			(at 259.15 60.4 0)
			(layer "F.Fab")
			(hide yes)
			(effects
				(font
					(size 1 1)
					(thickness 0.15)
				)
			)
		)
		(property "Dielectric" ""
			(at 259.15 60.4 0)
			(layer "F.Fab")
			(hide yes)
			(effects
				(font
					(size 1 1)
					(thickness 0.15)
				)
			)
		)
		(property "License" "Apache-2.0"
			(at 259.15 60.4 0)
			(layer "F.Fab")
			(hide yes)
			(effects
				(font
					(size 1 1)
					(thickness 0.15)
				)
			)
		)
		(property "MPN" "0402X104K6R3CT"
			(at 259.15 60.4 0)
			(layer "F.Fab")
			(hide yes)
			(effects
				(font
					(size 1 1)
					(thickness 0.15)
				)
			)
		)
		(property "Manufacturer" "Walsin"
			(at 259.15 60.4 0)
			(layer "F.Fab")
			(hide yes)
			(effects
				(font
					(size 1 1)
					(thickness 0.15)
				)
			)
		)
		(property "Public" "False"
			(at 259.15 60.4 0)
			(layer "F.Fab")
			(hide yes)
			(effects
				(font
					(size 1 1)
					(thickness 0.15)
				)
			)
		)
		(property "Val" "100n"
			(at 259.15 60.4 0)
			(layer "F.Fab")
			(hide yes)
			(effects
				(font
					(size 1 1)
					(thickness 0.15)
				)
			)
		)
		(property "Voltage" ""
			(at 259.15 60.4 0)
			(layer "F.Fab")
			(hide yes)
			(effects
				(font
					(size 1 1)
					(thickness 0.15)
				)
			)
		)
		(sheetname "/DDR3/")
		(sheetfile "ddr3.kicad_sch")
		(attr smd)
		(fp_rect
			(start -0.925 -0.47)
			(end 0.925 0.47)
			(stroke
				(width 0.05)
				(type default)
			)
			(fill no)
			(layer "F.CrtYd")
		)
		(fp_line
			(start 0.504 -0.25)
			(end 0.504 0.248)
			(stroke
				(width 0.15)
				(type solid)
			)
			(layer "F.Fab")
		)
		(fp_line
			(start -0.494 -0.25)
			(end 0.504 -0.25)
			(stroke
				(width 0.15)
				(type solid)
			)
			(layer "F.Fab")
		)
		(fp_line
			(start 0.504 0.248)
			(end -0.494 0.248)
			(stroke
				(width 0.15)
				(type solid)
			)
			(layer "F.Fab")
		)
		(fp_line
			(start -0.494 0.248)
			(end -0.494 -0.25)
			(stroke
				(width 0.15)
				(type solid)
			)
			(layer "F.Fab")
		)
		(pad "1" smd roundrect
			(at -0.48 0 90)
			(size 0.59 0.64)
			(layers "F.Cu" "F.Mask" "F.Paste")
			(roundrect_rratio 0.25)
			(net 1 "GND")
			(pintype "passive")
		)
		(pad "2" smd roundrect
			(at 0.48 0 90)
			(size 0.59 0.64)
			(layers "F.Cu" "F.Mask" "F.Paste")
			(roundrect_rratio 0.25)
			(net 3 "VCC1V35")
			(pintype "passive")
		)
	)
	(footprint "antmicro-footprints:C_Pol_EIA-D"
		(layer "F.Cu")
		(at 74.075 80.075 180)
		(property "Reference" "C150"
			(at 3.65 1.875 0)
			(layer "F.SilkS")
			(effects
				(font
					(size 0.7 0.7)
					(thickness 0.15)
				)
				(justify right bottom)
			)
		)
		(property "Value" "C_Pol_330u_6.3V_KEMET-T520-D"
			(at 0 3.6 0)
			(layer "F.Fab")
			(effects
				(font
					(size 0.7 0.7)
					(thickness 0.15)
				)
				(justify right bottom)
			)
		)
		(property "Datasheet" "https://www.kemet.com/en/us/capacitors/product/T520D337M006ATE045.html"
			(at 0 0 180)
			(layer "F.Fab")
			(hide yes)
			(effects
				(font
					(size 1.27 1.27)
					(thickness 0.15)
				)
			)
		)
		(property "Description" "Tantalum Polymer Capacitor, KO-CAP®, 330 µF, ± 20%, 6.3 V, D, 0.045 ohm, 2917 [7343 Metric]"
			(at 0 0 180)
			(layer "F.Fab")
			(hide yes)
			(effects
				(font
					(size 1.27 1.27)
					(thickness 0.15)
				)
			)
		)
		(property "Author" "Antmicro"
			(at 148.15 160.15 0)
			(layer "F.Fab")
			(hide yes)
			(effects
				(font
					(size 1 1)
					(thickness 0.15)
				)
			)
		)
		(property "Dielectric" "template_dielectric"
			(at 148.15 160.15 0)
			(layer "F.Fab")
			(hide yes)
			(effects
				(font
					(size 1 1)
					(thickness 0.15)
				)
			)
		)
		(property "License" "Apache-2.0"
			(at 148.15 160.15 0)
			(layer "F.Fab")
			(hide yes)
			(effects
				(font
					(size 1 1)
					(thickness 0.15)
				)
			)
		)
		(property "MPN" "T520D337M006ATE045"
			(at 148.15 160.15 0)
			(layer "F.Fab")
			(hide yes)
			(effects
				(font
					(size 1 1)
					(thickness 0.15)
				)
			)
		)
		(property "Manufacturer" "KEMET"
			(at 148.15 160.15 0)
			(layer "F.Fab")
			(hide yes)
			(effects
				(font
					(size 1 1)
					(thickness 0.15)
				)
			)
		)
		(property "Val" "330u"
			(at 148.15 160.15 0)
			(layer "F.Fab")
			(hide yes)
			(effects
				(font
					(size 1 1)
					(thickness 0.15)
				)
			)
		)
		(property "Voltage" "6.3V"
			(at 148.15 160.15 0)
			(layer "F.Fab")
			(hide yes)
			(effects
				(font
					(size 1 1)
					(thickness 0.15)
				)
			)
		)
		(property "DNP" ""
			(at 0 0 180)
			(unlocked yes)
			(layer "F.Fab")
			(hide yes)
			(effects
				(font
					(size 1 1)
					(thickness 0.15)
				)
			)
		)
		(sheetname "/FPGA power supply/")
		(sheetfile "fpga-power-supply.kicad_sch")
		(attr smd)
		(fp_line
			(start 3.6 2.2)
			(end -3.58 2.2)
			(stroke
				(width 0.15)
				(type solid)
			)
			(layer "F.SilkS")
		)
		(fp_line
			(start 3.6 1.6)
			(end 3.6 2.2)
			(stroke
				(width 0.15)
				(type solid)
			)
			(layer "F.SilkS")
		)
		(fp_line
			(start 3.6 -2.2)
			(end 3.6 -1.6)
			(stroke
				(width 0.15)
				(type solid)
			)
			(layer "F.SilkS")
		)
		(fp_line
			(start -3.58 2.2)
			(end -3.58 1.6)
			(stroke
				(width 0.15)
				(type solid)
			)
			(layer "F.SilkS")
		)
		(fp_line
			(start -3.58 -1.6)
			(end -3.58 -2.2)
			(stroke
				(width 0.15)
				(type solid)
			)
			(layer "F.SilkS")
		)
		(fp_line
			(start -3.58 -2.2)
			(end 3.6 -2.2)
			(stroke
				(width 0.15)
				(type solid)
			)
			(layer "F.SilkS")
		)
		(fp_line
			(start -4.1 -2.025)
			(end -4.1 -1.625)
			(stroke
				(width 0.12)
				(type solid)
			)
			(layer "F.SilkS")
		)
		(fp_line
			(start -4.3 -1.825)
			(end -3.9 -1.825)
			(stroke
				(width 0.12)
				(type solid)
			)
			(layer "F.SilkS")
		)
		(fp_line
			(start 4.505 1.51)
			(end 3.77 1.51)
			(stroke
				(width 0.05)
				(type solid)
			)
			(layer "F.CrtYd")
		)
		(fp_line
			(start 4.505 -1.51)
			(end 4.505 1.5)
			(stroke
				(width 0.05)
				(type solid)
			)
			(layer "F.CrtYd")
		)
		(fp_line
			(start 3.77 2.4)
			(end -3.77 2.4)
			(stroke
				(width 0.05)
				(type solid)
			)
			(layer "F.CrtYd")
		)
		(fp_line
			(start 3.77 1.51)
			(end 3.77 2.4)
			(stroke
				(width 0.05)
				(type solid)
			)
			(layer "F.CrtYd")
		)
		(fp_line
			(start 3.77 -1.51)
			(end 4.505 -1.51)
			(stroke
				(width 0.05)
				(type solid)
			)
			(layer "F.CrtYd")
		)
		(fp_line
			(start 3.77 -2.4)
			(end 3.77 -1.51)
			(stroke
				(width 0.05)
				(type solid)
			)
			(layer "F.CrtYd")
		)
		(fp_line
			(start -3.77 2.4)
			(end -3.77 1.51)
			(stroke
				(width 0.05)
				(type solid)
			)
			(layer "F.CrtYd")
		)
		(fp_line
			(start -3.77 1.51)
			(end -4.505 1.51)
			(stroke
				(width 0.05)
				(type solid)
			)
			(layer "F.CrtYd")
		)
		(fp_line
			(start -3.775 -1.5)
			(end -4.505 -1.5)
			(stroke
				(width 0.05)
				(type solid)
			)
			(layer "F.CrtYd")
		)
		(fp_line
			(start -3.775 -2.4)
			(end 3.77 -2.4)
			(stroke
				(width 0.05)
				(type solid)
			)
			(layer "F.CrtYd")
		)
		(fp_line
			(start -3.775 -2.4)
			(end -3.775 -1.5)
			(stroke
				(width 0.05)
				(type solid)
			)
			(layer "F.CrtYd")
		)
		(fp_line
			(start -4.505 1.51)
			(end -4.505 -1.5)
			(stroke
				(width 0.05)
				(type solid)
			)
			(layer "F.CrtYd")
		)
		(fp_rect
			(start -3.65 -2.15)
			(end 3.65 2.15)
			(stroke
				(width 0.15)
				(type solid)
			)
			(fill no)
			(layer "F.Fab")
		)
		(pad "1" smd roundrect
			(at -3.1 0 180)
			(size 2.31 2.52)
			(layers "F.Cu" "F.Mask" "F.Paste")
			(roundrect_rratio 0.1)
			(net 6 "VCC1V0")
			(pintype "passive")
		)
		(pad "2" smd roundrect
			(at 3.1 0 180)
			(size 2.31 2.52)
			(layers "F.Cu" "F.Mask" "F.Paste")
			(roundrect_rratio 0.1)
			(net 1 "GND")
			(pintype "passive")
		)
	)
	(footprint "antmicro-footprints:C_0402_1005Metric"
		(layer "F.Cu")
		(at 85.895 79.425 180)
		(descr "Capacitor SMD 0402")
		(tags "capacitor SMD 0402")
		(property "Reference" "C85"
			(at -5.705 -0.375 0)
			(layer "F.SilkS")
			(effects
				(font
					(size 0.7 0.7)
					(thickness 0.15)
				)
				(justify right bottom)
			)
		)
		(property "Value" "C_10u_0402"
			(at 0 1.4 0)
			(layer "F.Fab")
			(effects
				(font
					(size 0.7 0.7)
					(thickness 0.15)
				)
				(justify right bottom)
			)
		)
		(property "Datasheet" "https://www.yageo.com/en/Chart/Download/pdf/CC0402MRX5R5BB106"
			(at 0 0 180)
			(layer "F.Fab")
			(hide yes)
			(effects
				(font
					(size 1.27 1.27)
					(thickness 0.15)
				)
			)
		)
		(property "Description" "SMD Multilayer Ceramic Capacitor, 10 µF, 6.3 V, 0402 [1005 Metric], ± 20%, X5R, CC Series"
			(at 0 0 180)
			(layer "F.Fab")
			(hide yes)
			(effects
				(font
					(size 1.27 1.27)
					(thickness 0.15)
				)
			)
		)
		(property "Author" "Antmicro"
			(at 171.79 158.85 0)
			(layer "F.Fab")
			(hide yes)
			(effects
				(font
					(size 1 1)
					(thickness 0.15)
				)
			)
		)
		(property "Dielectric" ""
			(at 171.79 158.85 0)
			(layer "F.Fab")
			(hide yes)
			(effects
				(font
					(size 1 1)
					(thickness 0.15)
				)
			)
		)
		(property "License" "Apache-2.0"
			(at 171.79 158.85 0)
			(layer "F.Fab")
			(hide yes)
			(effects
				(font
					(size 1 1)
					(thickness 0.15)
				)
			)
		)
		(property "MPN" "CC0402MRX5R5BB106"
			(at 171.79 158.85 0)
			(layer "F.Fab")
			(hide yes)
			(effects
				(font
					(size 1 1)
					(thickness 0.15)
				)
			)
		)
		(property "Manufacturer" "YAGEO"
			(at 171.79 158.85 0)
			(layer "F.Fab")
			(hide yes)
			(effects
				(font
					(size 1 1)
					(thickness 0.15)
				)
			)
		)
		(property "Val" "10u"
			(at 171.79 158.85 0)
			(layer "F.Fab")
			(hide yes)
			(effects
				(font
					(size 1 1)
					(thickness 0.15)
				)
			)
		)
		(property "Voltage" ""
			(at 171.79 158.85 0)
			(layer "F.Fab")
			(hide yes)
			(effects
				(font
					(size 1 1)
					(thickness 0.15)
				)
			)
		)
		(sheetname "/Power supply/")
		(sheetfile "power-supply.kicad_sch")
		(attr smd)
		(fp_rect
			(start -0.925 -0.47)
			(end 0.925 0.47)
			(stroke
				(width 0.05)
				(type default)
			)
			(fill no)
			(layer "F.CrtYd")
		)
		(fp_line
			(start 0.504 0.248)
			(end -0.494 0.248)
			(stroke
				(width 0.15)
				(type solid)
			)
			(layer "F.Fab")
		)
		(fp_line
			(start 0.504 -0.25)
			(end 0.504 0.248)
			(stroke
				(width 0.15)
				(type solid)
			)
			(layer "F.Fab")
		)
		(fp_line
			(start -0.494 0.248)
			(end -0.494 -0.25)
			(stroke
				(width 0.15)
				(type solid)
			)
			(layer "F.Fab")
		)
		(fp_line
			(start -0.494 -0.25)
			(end 0.504 -0.25)
			(stroke
				(width 0.15)
				(type solid)
			)
			(layer "F.Fab")
		)
		(pad "1" smd roundrect
			(at -0.48 0 180)
			(size 0.59 0.64)
			(layers "F.Cu" "F.Mask" "F.Paste")
			(roundrect_rratio 0.25)
			(net 1 "GND")
			(pintype "passive")
		)
		(pad "2" smd roundrect
			(at 0.48 0 180)
			(size 0.59 0.64)
			(layers "F.Cu" "F.Mask" "F.Paste")
			(roundrect_rratio 0.25)
			(net 276 "Net-(C81-Pad2)")
			(pintype "passive")
		)
	)
	(footprint "antmicro-footprints:R_0402_1005Metric"
		(layer "F.Cu")
		(at 89.549 81.827 90)
		(descr "Resistor SMD 0402")
		(tags "resistor SMD 0402")
		(property "Reference" "R78"
			(at -1.073 3.351 90)
			(layer "F.SilkS")
			(effects
				(font
					(size 0.7 0.7)
					(thickness 0.15)
				)
				(justify left bottom)
			)
		)
		(property "Value" "R_100k_0402"
			(at 0 1.4 90)
			(layer "F.Fab")
			(effects
				(font
					(size 0.7 0.7)
					(thickness 0.15)
				)
				(justify left bottom)
			)
		)
		(property "Datasheet" "https://www.bourns.com/docs/product-datasheets/cr.pdf"
			(at 0 0 90)
			(layer "F.Fab")
			(hide yes)
			(effects
				(font
					(size 1.27 1.27)
					(thickness 0.15)
				)
			)
		)
		(property "Description" "SMD Chip Resistor, 100 kohm, ± 1%, 62.5 mW, 0402 [1005 Metric], Thick Film, General Purpose"
			(at 0 0 90)
			(layer "F.Fab")
			(hide yes)
			(effects
				(font
					(size 1.27 1.27)
					(thickness 0.15)
				)
			)
		)
		(property "Author" "Antmicro"
			(at 171.376 -7.722 0)
			(layer "F.Fab")
			(hide yes)
			(effects
				(font
					(size 1 1)
					(thickness 0.15)
				)
			)
		)
		(property "License" "Apache-2.0"
			(at 171.376 -7.722 0)
			(layer "F.Fab")
			(hide yes)
			(effects
				(font
					(size 1 1)
					(thickness 0.15)
				)
			)
		)
		(property "MPN" "CR0402-FX-1003GLF"
			(at 171.376 -7.722 0)
			(layer "F.Fab")
			(hide yes)
			(effects
				(font
					(size 1 1)
					(thickness 0.15)
				)
			)
		)
		(property "Manufacturer" "Bourns"
			(at 171.376 -7.722 0)
			(layer "F.Fab")
			(hide yes)
			(effects
				(font
					(size 1 1)
					(thickness 0.15)
				)
			)
		)
		(property "Tolerance" "1%"
			(at 171.376 -7.722 0)
			(layer "F.Fab")
			(hide yes)
			(effects
				(font
					(size 1 1)
					(thickness 0.15)
				)
			)
		)
		(property "Val" "100k"
			(at 171.376 -7.722 0)
			(layer "F.Fab")
			(hide yes)
			(effects
				(font
					(size 1 1)
					(thickness 0.15)
				)
			)
		)
		(sheetname "/Power supply/")
		(sheetfile "power-supply.kicad_sch")
		(attr smd)
		(fp_rect
			(start -0.925 -0.47)
			(end 0.925 0.47)
			(stroke
				(width 0.05)
				(type default)
			)
			(fill no)
			(layer "F.CrtYd")
		)
		(fp_rect
			(start -0.5 -0.25)
			(end 0.5 0.25)
			(stroke
				(width 0.15)
				(type solid)
			)
			(fill no)
			(layer "F.Fab")
		)
		(pad "1" smd roundrect
			(at -0.48 0 90)
			(size 0.59 0.64)
			(layers "F.Cu" "F.Mask" "F.Paste")
			(roundrect_rratio 0.25)
			(net 195 "Net-(U12-FB)")
			(pintype "passive")
		)
		(pad "2" smd roundrect
			(at 0.48 0 90)
			(size 0.59 0.64)
			(layers "F.Cu" "F.Mask" "F.Paste")
			(roundrect_rratio 0.25)
			(net 1 "GND")
			(pintype "passive")
		)
	)
	(footprint "antmicro-footprints:QFN-8_2x1.5mm"
		(layer "F.Cu")
		(at 86.995 82.025 180)
		(property "Reference" "U12"
			(at 0.305 -2.205 180)
			(layer "F.SilkS")
			(effects
				(font
					(size 0.7 0.7)
					(thickness 0.15)
				)
				(justify left bottom)
			)
		)
		(property "Value" "TPS62823DLCT"
			(at 0 2.2 180)
			(layer "F.Fab")
			(effects
				(font
					(size 0.7 0.7)
					(thickness 0.15)
				)
				(justify left bottom)
			)
		)
		(property "Datasheet" "https://www.ti.com/lit/ds/symlink/tps62823.pdf?ts=1685970309606&ref_url=https%253A%252F%252Fwww.ti.com%252Fproduct%252FTPS62823%252Fpart-details%252FTPS62823DLCT"
			(at 0 0 180)
			(layer "F.Fab")
			(hide yes)
			(effects
				(font
					(size 1.27 1.27)
					(thickness 0.15)
				)
			)
		)
		(property "Description" "DC/DC converter"
			(at 0 0 180)
			(layer "F.Fab")
			(hide yes)
			(effects
				(font
					(size 1.27 1.27)
					(thickness 0.15)
				)
			)
		)
		(property "Author" "Antmicro"
			(at 173.99 164.05 0)
			(layer "F.Fab")
			(hide yes)
			(effects
				(font
					(size 1 1)
					(thickness 0.15)
				)
			)
		)
		(property "License" "Apache-2.0"
			(at 173.99 164.05 0)
			(layer "F.Fab")
			(hide yes)
			(effects
				(font
					(size 1 1)
					(thickness 0.15)
				)
			)
		)
		(property "MPN" "TPS62823DLCT"
			(at 173.99 164.05 0)
			(layer "F.Fab")
			(hide yes)
			(effects
				(font
					(size 1 1)
					(thickness 0.15)
				)
			)
		)
		(property "Manufacturer" "Texas Instruments"
			(at 173.99 164.05 0)
			(layer "F.Fab")
			(hide yes)
			(effects
				(font
					(size 1 1)
					(thickness 0.15)
				)
			)
		)
		(sheetname "/Power supply/")
		(sheetfile "power-supply.kicad_sch")
		(attr smd)
		(fp_line
			(start -0.25 -1.05)
			(end 0.9 -1.05)
			(stroke
				(width 0.15)
				(type solid)
			)
			(layer "F.SilkS")
		)
		(fp_line
			(start -0.9 1.05)
			(end 0.9 1.05)
			(stroke
				(width 0.15)
				(type solid)
			)
			(layer "F.SilkS")
		)
		(fp_circle
			(center -0.9 -1.05)
			(end -0.849 -1.05)
			(stroke
				(width 0.15)
				(type solid)
			)
			(fill yes)
			(layer "F.SilkS")
		)
		(fp_rect
			(start -1.1 -1.25)
			(end 1.1 1.25)
			(stroke
				(width 0.05)
				(type solid)
			)
			(fill no)
			(layer "F.CrtYd")
		)
		(fp_line
			(start 0.998 0.998)
			(end -1 0.998)
			(stroke
				(width 0.15)
				(type solid)
			)
			(layer "F.Fab")
		)
		(fp_line
			(start 0.998 -1)
			(end 0.998 0.998)
			(stroke
				(width 0.15)
				(type solid)
			)
			(layer "F.Fab")
		)
		(fp_line
			(start -0.5 -1)
			(end 0.998 -1)
			(stroke
				(width 0.15)
				(type solid)
			)
			(layer "F.Fab")
		)
		(fp_line
			(start -1 0.998)
			(end -1 -0.5)
			(stroke
				(width 0.15)
				(type solid)
			)
			(layer "F.Fab")
		)
		(fp_line
			(start -1 -0.5)
			(end -0.5 -1)
			(stroke
				(width 0.15)
				(type solid)
			)
			(layer "F.Fab")
		)
		(pad "1" smd rect
			(at -0.677 -0.75 180)
			(size 0.55 0.25)
			(layers "F.Cu" "F.Mask" "F.Paste")
			(net 319 "Net-(U12-EN)")
			(pinfunction "EN")
			(pintype "input")
		)
		(pad "2" smd rect
			(at -0.677 -0.25 180)
			(size 0.55 0.25)
			(layers "F.Cu" "F.Mask" "F.Paste")
			(net 195 "Net-(U12-FB)")
			(pinfunction "FB")
			(pintype "bidirectional")
		)
		(pad "3" smd rect
			(at -0.677 0.248 180)
			(size 0.55 0.25)
			(layers "F.Cu" "F.Mask" "F.Paste")
			(net 1 "GND")
			(pinfunction "AGND")
			(pintype "power_in")
		)
		(pad "4" smd rect
			(at -0.677 0.748 180)
			(size 0.55 0.25)
			(layers "F.Cu" "F.Mask" "F.Paste")
			(net 531 "unconnected-(U12-NC-Pad4)")
			(pinfunction "NC")
			(pintype "no_connect")
		)
		(pad "5" smd rect
			(at 0.675 0.748 180)
			(size 0.55 0.25)
			(layers "F.Cu" "F.Mask" "F.Paste")
			(net 1 "GND")
			(pinfunction "PGND")
			(pintype "power_in")
		)
		(pad "6" smd rect
			(at 0.675 0.248 180)
			(size 0.55 0.25)
			(layers "F.Cu" "F.Mask" "F.Paste")
			(net 289 "Net-(U12-SW)")
			(pinfunction "SW")
			(pintype "bidirectional")
		)
		(pad "7" smd rect
			(at 0.675 -0.25 180)
			(size 0.55 0.25)
			(layers "F.Cu" "F.Mask" "F.Paste")
			(net 4 "VCC5V0")
			(pinfunction "VIN")
			(pintype "power_in")
		)
		(pad "8" smd rect
			(at 0.675 -0.75 180)
			(size 0.55 0.25)
			(layers "F.Cu" "F.Mask" "F.Paste")
			(net 538 "1V0_PG")
			(pinfunction "PG")
			(pintype "output")
		)
	)
)
